(kicad_pcb
	(version 20241229)
	(generator "pcbnew")
	(generator_version "9.0")
	(general
		(thickness 1.62)
		(legacy_teardrops no)
	)
	(paper "A3")
	(title_block
		(title "COM Express 7 Baseboard")
		(date "2025-02-04")
		(rev "1.1.2")
		(company "Antmicro Ltd")
		(comment 1 "www.antmicro.com")
		(comment 9 "footprints 448-452 of 802")
	)
	(layers
		(0 "F.Cu" signal)
		(4 "In1.Cu" signal)
		(6 "In2.Cu" signal)
		(8 "In3.Cu" signal)
		(10 "In4.Cu" signal)
		(12 "In5.Cu" signal)
		(14 "In6.Cu" signal)
		(2 "B.Cu" signal)
		(9 "F.Adhes" user "F.Adhesive")
		(11 "B.Adhes" user "B.Adhesive")
		(13 "F.Paste" user)
		(15 "B.Paste" user)
		(5 "F.SilkS" user "F.Silkscreen")
		(7 "B.SilkS" user "B.Silkscreen")
		(1 "F.Mask" user)
		(3 "B.Mask" user)
		(17 "Dwgs.User" user "User.Drawings")
		(19 "Cmts.User" user "User.Comments")
		(21 "Eco1.User" user "User.Eco1")
		(23 "Eco2.User" user "User.Eco2")
		(25 "Edge.Cuts" user)
		(27 "Margin" user)
		(31 "F.CrtYd" user "F.Courtyard")
		(29 "B.CrtYd" user "B.Courtyard")
		(35 "F.Fab" user)
		(33 "B.Fab" user)
	)
	(footprint "antmicro-footprints:PinHeader_1x3_P2.54mm_Drill1.1mm"
		(layer "F.Cu")
		(at 175.631 70.61)
		(property "Reference" "J7"
			(at -1.641 1.44 90)
			(layer "F.SilkS")
			(effects
				(font
					(size 0.7 0.7)
					(thickness 0.15)
				)
				(justify left bottom)
			)
		)
		(property "Value" "PinHeader_1x3_P2.54mm_Drill1.1mm"
			(at -1.6 2.7 0)
			(layer "F.Fab")
			(effects
				(font
					(size 0.7 0.7)
					(thickness 0.15)
				)
				(justify left bottom)
			)
		)
		(property "Datasheet" "https://katalog.we-online.de/em/datasheet/6130xx11121.pdf"
			(at 0 0 0)
			(layer "F.Fab")
			(hide yes)
			(effects
				(font
					(size 1.27 1.27)
					(thickness 0.15)
				)
			)
		)
		(property "MPN" "61300311121"
			(at 0 0 0)
			(unlocked yes)
			(layer "F.Fab")
			(hide yes)
			(effects
				(font
					(size 1 1)
					(thickness 0.15)
				)
			)
		)
		(property "Manufacturer" "Würth Elektronik"
			(at 0 0 0)
			(unlocked yes)
			(layer "F.Fab")
			(hide yes)
			(effects
				(font
					(size 1 1)
					(thickness 0.15)
				)
			)
		)
		(property "Author" "Antmicro"
			(at 0 0 0)
			(unlocked yes)
			(layer "F.Fab")
			(hide yes)
			(effects
				(font
					(size 1 1)
					(thickness 0.15)
				)
			)
		)
		(property "License" "Apache-2.0"
			(at 0 0 0)
			(unlocked yes)
			(layer "F.Fab")
			(hide yes)
			(effects
				(font
					(size 1 1)
					(thickness 0.15)
				)
			)
		)
		(sheetname "Com Express 7 MGMT")
		(sheetfile "com_express_7_mgmt.kicad_sch")
		(attr through_hole)
		(fp_line
			(start -1.401 -1.401)
			(end -1.401 -0.902)
			(stroke
				(width 0.15)
				(type solid)
			)
			(layer "F.SilkS")
		)
		(fp_line
			(start -1.401 -1.401)
			(end -0.902 -1.401)
			(stroke
				(width 0.15)
				(type solid)
			)
			(layer "F.SilkS")
		)
		(fp_line
			(start -1.401 1.398)
			(end -1.401 0.9)
			(stroke
				(width 0.15)
				(type solid)
			)
			(layer "F.SilkS")
		)
		(fp_line
			(start -1.401 1.398)
			(end -0.902 1.398)
			(stroke
				(width 0.15)
				(type solid)
			)
			(layer "F.SilkS")
		)
		(fp_line
			(start 6.499 -1.401)
			(end 5.999 -1.401)
			(stroke
				(width 0.15)
				(type solid)
			)
			(layer "F.SilkS")
		)
		(fp_line
			(start 6.499 -1.401)
			(end 6.499 -0.902)
			(stroke
				(width 0.15)
				(type solid)
			)
			(layer "F.SilkS")
		)
		(fp_line
			(start 6.499 1.398)
			(end 5.999 1.398)
			(stroke
				(width 0.15)
				(type solid)
			)
			(layer "F.SilkS")
		)
		(fp_line
			(start 6.499 1.398)
			(end 6.499 0.9)
			(stroke
				(width 0.15)
				(type solid)
			)
			(layer "F.SilkS")
		)
		(fp_line
			(start -1.52 -1.52)
			(end -1.52 1.5)
			(stroke
				(width 0.05)
				(type solid)
			)
			(layer "F.CrtYd")
		)
		(fp_line
			(start -1.52 -1.52)
			(end 6.58 -1.52)
			(stroke
				(width 0.05)
				(type solid)
			)
			(layer "F.CrtYd")
		)
		(fp_line
			(start -1.52 1.5)
			(end 6.58 1.5)
			(stroke
				(width 0.05)
				(type solid)
			)
			(layer "F.CrtYd")
		)
		(fp_line
			(start 6.58 -1.52)
			(end 6.58 1.5)
			(stroke
				(width 0.05)
				(type solid)
			)
			(layer "F.CrtYd")
		)
		(fp_line
			(start -1.27 -1.27)
			(end -1.27 1.269)
			(stroke
				(width 0.15)
				(type solid)
			)
			(layer "F.Fab")
		)
		(fp_line
			(start -1.27 -1.27)
			(end 6.349 -1.27)
			(stroke
				(width 0.15)
				(type solid)
			)
			(layer "F.Fab")
		)
		(fp_line
			(start -1.27 1.269)
			(end 6.349 1.269)
			(stroke
				(width 0.15)
				(type solid)
			)
			(layer "F.Fab")
		)
		(fp_line
			(start 6.349 -1.27)
			(end 6.349 1.269)
			(stroke
				(width 0.15)
				(type solid)
			)
			(layer "F.Fab")
		)
		(pad "1" thru_hole rect
			(at 0 0)
			(size 1.7 1.7)
			(drill 1.1)
			(layers "*.Cu" "*.Mask")
			(remove_unused_layers no)
			(net 1000 "unconnected-(J7-Pad1)")
			(pintype "passive+no_connect")
			(teardrops
				(best_length_ratio 0.2)
				(max_length 1)
				(best_width_ratio 0.9)
				(max_width 2)
				(curved_edges yes)
				(filter_ratio 0.9)
				(enabled yes)
				(allow_two_segments yes)
				(prefer_zone_connections yes)
			)
		)
		(pad "2" thru_hole circle
			(at 2.539 0)
			(size 1.7 1.7)
			(drill 1.1)
			(layers "*.Cu" "*.Mask")
			(remove_unused_layers no)
			(net 999 "Net-(C101-Pad1)")
			(pintype "passive")
			(teardrops
				(best_length_ratio 0.4)
				(max_length 1)
				(best_width_ratio 0.9)
				(max_width 2)
				(curved_edges yes)
				(filter_ratio 0.9)
				(enabled yes)
				(allow_two_segments yes)
				(prefer_zone_connections yes)
			)
		)
		(pad "3" thru_hole circle
			(at 5.078 0)
			(size 1.7 1.7)
			(drill 1.1)
			(layers "*.Cu" "*.Mask")
			(remove_unused_layers no)
			(net 83 "Net-(Q11-D)")
			(pintype "passive")
			(teardrops
				(best_length_ratio 0.4)
				(max_length 1)
				(best_width_ratio 0.9)
				(max_width 2)
				(curved_edges yes)
				(filter_ratio 0.9)
				(enabled yes)
				(allow_two_segments yes)
				(prefer_zone_connections yes)
			)
		)
	)
	(footprint "antmicro-footprints:R_0402_1005Metric"
		(layer "F.Cu")
		(at 252.665 86.449999)
		(descr "Resistor SMD 0402")
		(tags "resistor SMD 0402")
		(property "Reference" "R150"
			(at -0.865 0.440001 0)
			(layer "F.SilkS")
			(effects
				(font
					(size 0.7 0.7)
					(thickness 0.15)
				)
				(justify right bottom)
			)
		)
		(property "Value" "R_0R_0402"
			(at -1.011843 1.772047 0)
			(layer "F.Fab")
			(effects
				(font
					(size 0.7 0.7)
					(thickness 0.15)
				)
				(justify left bottom)
			)
		)
		(property "Datasheet" "https://industrial.panasonic.com/cdbs/www-data/pdf/RDA0000/AOA0000C301.pdf"
			(at 0 0 0)
			(layer "F.Fab")
			(hide yes)
			(effects
				(font
					(size 1.27 1.27)
					(thickness 0.15)
				)
			)
		)
		(property "Author" "Antmicro"
			(at 0 0 0)
			(layer "F.Fab")
			(hide yes)
			(effects
				(font
					(size 1 1)
					(thickness 0.15)
				)
			)
		)
		(property "Current" "1A"
			(at 0 0 0)
			(layer "F.Fab")
			(hide yes)
			(effects
				(font
					(size 1 1)
					(thickness 0.15)
				)
			)
		)
		(property "License" "Apache-2.0"
			(at 0 0 0)
			(layer "F.Fab")
			(hide yes)
			(effects
				(font
					(size 1 1)
					(thickness 0.15)
				)
			)
		)
		(property "MPN" "ERJ2GE0R00X"
			(at 0 0 0)
			(layer "F.Fab")
			(hide yes)
			(effects
				(font
					(size 1 1)
					(thickness 0.15)
				)
			)
		)
		(property "Manufacturer" "Panasonic"
			(at 0 0 0)
			(layer "F.Fab")
			(hide yes)
			(effects
				(font
					(size 1 1)
					(thickness 0.15)
				)
			)
		)
		(property "Public" "False"
			(at 0 0 0)
			(layer "F.Fab")
			(hide yes)
			(effects
				(font
					(size 1 1)
					(thickness 0.15)
				)
			)
		)
		(property "Tolerance" ""
			(at 0 0 0)
			(layer "F.Fab")
			(hide yes)
			(effects
				(font
					(size 1 1)
					(thickness 0.15)
				)
			)
		)
		(property "Val" "0R"
			(at 0 0 0)
			(layer "F.Fab")
			(hide yes)
			(effects
				(font
					(size 1 1)
					(thickness 0.15)
				)
			)
		)
		(sheetname "Misc")
		(sheetfile "misc.kicad_sch")
		(attr smd)
		(fp_rect
			(start -0.925 -0.47)
			(end 0.925 0.47)
			(stroke
				(width 0.05)
				(type default)
			)
			(fill no)
			(layer "F.CrtYd")
		)
		(fp_rect
			(start -0.5 -0.25)
			(end 0.5 0.25)
			(stroke
				(width 0.15)
				(type solid)
			)
			(fill no)
			(layer "F.Fab")
		)
		(pad "1" smd roundrect
			(at -0.48 0)
			(size 0.59 0.64)
			(layers "F.Cu" "F.Mask" "F.Paste")
			(roundrect_rratio 0.25)
			(net 52 "+5V")
			(pintype "passive")
			(teardrops
				(best_length_ratio 0.2)
				(max_length 1)
				(best_width_ratio 0.9)
				(max_width 2)
				(curved_edges yes)
				(filter_ratio 0.9)
				(enabled yes)
				(allow_two_segments yes)
				(prefer_zone_connections yes)
			)
		)
		(pad "2" smd roundrect
			(at 0.48 0)
			(size 0.59 0.64)
			(layers "F.Cu" "F.Mask" "F.Paste")
			(roundrect_rratio 0.25)
			(net 592 "Net-(U24-+5V_{IN})")
			(pintype "passive")
			(teardrops
				(best_length_ratio 0.2)
				(max_length 1)
				(best_width_ratio 0.9)
				(max_width 2)
				(curved_edges yes)
				(filter_ratio 0.9)
				(enabled yes)
				(allow_two_segments yes)
				(prefer_zone_connections yes)
			)
		)
	)
	(footprint "antmicro-footprints:R_0402_1005Metric"
		(layer "F.Cu")
		(at 161.55 156.81 -90)
		(descr "Resistor SMD 0402")
		(tags "resistor SMD 0402")
		(property "Reference" "R34"
			(at -3.013 -0.449 90)
			(layer "F.SilkS")
			(effects
				(font
					(size 0.7 0.7)
					(thickness 0.15)
				)
				(justify right bottom)
			)
		)
		(property "Value" "R_0R_0402"
			(at -1.011843 1.772047 90)
			(layer "F.Fab")
			(effects
				(font
					(size 0.7 0.7)
					(thickness 0.15)
				)
				(justify right bottom)
			)
		)
		(property "Datasheet" "https://industrial.panasonic.com/cdbs/www-data/pdf/RDA0000/AOA0000C301.pdf"
			(at 0 0 270)
			(layer "F.Fab")
			(hide yes)
			(effects
				(font
					(size 1.27 1.27)
					(thickness 0.15)
				)
			)
		)
		(property "Author" "Antmicro"
			(at 4.74 318.36 0)
			(layer "F.Fab")
			(hide yes)
			(effects
				(font
					(size 1 1)
					(thickness 0.15)
				)
			)
		)
		(property "Current" "1A"
			(at 4.74 318.36 0)
			(layer "F.Fab")
			(hide yes)
			(effects
				(font
					(size 1 1)
					(thickness 0.15)
				)
			)
		)
		(property "License" "Apache-2.0"
			(at 4.74 318.36 0)
			(layer "F.Fab")
			(hide yes)
			(effects
				(font
					(size 1 1)
					(thickness 0.15)
				)
			)
		)
		(property "MPN" "ERJ2GE0R00X"
			(at 4.74 318.36 0)
			(layer "F.Fab")
			(hide yes)
			(effects
				(font
					(size 1 1)
					(thickness 0.15)
				)
			)
		)
		(property "Manufacturer" "Panasonic"
			(at 4.74 318.36 0)
			(layer "F.Fab")
			(hide yes)
			(effects
				(font
					(size 1 1)
					(thickness 0.15)
				)
			)
		)
		(property "Public" "False"
			(at 4.74 318.36 0)
			(layer "F.Fab")
			(hide yes)
			(effects
				(font
					(size 1 1)
					(thickness 0.15)
				)
			)
		)
		(property "Tolerance" ""
			(at 4.74 318.36 0)
			(layer "F.Fab")
			(hide yes)
			(effects
				(font
					(size 1 1)
					(thickness 0.15)
				)
			)
		)
		(property "Val" "0R"
			(at 4.74 318.36 0)
			(layer "F.Fab")
			(hide yes)
			(effects
				(font
					(size 1 1)
					(thickness 0.15)
				)
			)
		)
		(sheetname "2xSFP+")
		(sheetfile "2xSFP+.kicad_sch")
		(attr smd)
		(fp_rect
			(start -0.925 -0.47)
			(end 0.925 0.47)
			(stroke
				(width 0.05)
				(type default)
			)
			(fill no)
			(layer "F.CrtYd")
		)
		(fp_rect
			(start -0.5 -0.25)
			(end 0.5 0.25)
			(stroke
				(width 0.15)
				(type solid)
			)
			(fill no)
			(layer "F.Fab")
		)
		(pad "1" smd roundrect
			(at -0.48 0 270)
			(size 0.59 0.64)
			(layers "F.Cu" "F.Mask" "F.Paste")
			(roundrect_rratio 0.25)
			(net 423 "/2xSFP+/I2C_{LED}.SCL")
			(pintype "passive")
			(teardrops
				(best_length_ratio 0.2)
				(max_length 1)
				(best_width_ratio 0.9)
				(max_width 2)
				(curved_edges yes)
				(filter_ratio 0.9)
				(enabled yes)
				(allow_two_segments yes)
				(prefer_zone_connections yes)
			)
		)
		(pad "2" smd roundrect
			(at 0.48 0 270)
			(size 0.59 0.64)
			(layers "F.Cu" "F.Mask" "F.Paste")
			(roundrect_rratio 0.25)
			(net 559 "Net-(U5-SCL)")
			(pintype "passive")
			(teardrops
				(best_length_ratio 0.2)
				(max_length 1)
				(best_width_ratio 0.9)
				(max_width 2)
				(curved_edges yes)
				(filter_ratio 0.9)
				(enabled yes)
				(allow_two_segments yes)
				(prefer_zone_connections yes)
			)
		)
	)
	(footprint "antmicro-footprints:SOD-523"
		(layer "F.Cu")
		(at 112.15 135.71)
		(property "Reference" "D29"
			(at 1 0.45 0)
			(layer "F.SilkS")
			(effects
				(font
					(size 0.7 0.7)
					(thickness 0.15)
				)
				(justify left bottom)
			)
		)
		(property "Value" "PESD5Z5_0F"
			(at 0 1.499 0)
			(layer "F.Fab")
			(effects
				(font
					(size 0.7 0.7)
					(thickness 0.15)
				)
				(justify left bottom)
			)
		)
		(property "Datasheet" "https://assets.nexperia.com/documents/data-sheet/PESD5Z5_0.pdf"
			(at 0 0 0)
			(layer "F.Fab")
			(hide yes)
			(effects
				(font
					(size 1.27 1.27)
					(thickness 0.15)
				)
			)
		)
		(property "Author" "Antmicro"
			(at 0 0 0)
			(layer "F.Fab")
			(hide yes)
			(effects
				(font
					(size 1 1)
					(thickness 0.15)
				)
			)
		)
		(property "License" "Apache-2.0"
			(at 0 0 0)
			(layer "F.Fab")
			(hide yes)
			(effects
				(font
					(size 1 1)
					(thickness 0.15)
				)
			)
		)
		(property "MPN" "PESD5Z5.0F"
			(at 0 0 0)
			(layer "F.Fab")
			(hide yes)
			(effects
				(font
					(size 1 1)
					(thickness 0.15)
				)
			)
		)
		(property "Manufacturer" "Nexperia"
			(at 0 0 0)
			(layer "F.Fab")
			(hide yes)
			(effects
				(font
					(size 1 1)
					(thickness 0.15)
				)
			)
		)
		(property "Public" "False"
			(at 0 0 0)
			(layer "F.Fab")
			(hide yes)
			(effects
				(font
					(size 1 1)
					(thickness 0.15)
				)
			)
		)
		(sheetname "SD card")
		(sheetfile "sd_card.kicad_sch")
		(attr smd)
		(fp_line
			(start -0.35 -0.5)
			(end -0.35 0.5)
			(stroke
				(width 0.15)
				(type solid)
			)
			(layer "F.SilkS")
		)
		(fp_rect
			(start -1 -0.6)
			(end 1 0.6)
			(stroke
				(width 0.05)
				(type solid)
			)
			(fill no)
			(layer "F.CrtYd")
		)
		(fp_line
			(start -0.652 -0.425)
			(end 0.65 -0.425)
			(stroke
				(width 0.15)
				(type solid)
			)
			(layer "F.Fab")
		)
		(fp_line
			(start -0.652 0.423)
			(end -0.652 -0.425)
			(stroke
				(width 0.15)
				(type solid)
			)
			(layer "F.Fab")
		)
		(fp_line
			(start -0.652 0.423)
			(end 0.65 0.423)
			(stroke
				(width 0.15)
				(type solid)
			)
			(layer "F.Fab")
		)
		(fp_line
			(start -0.35 -0.4)
			(end -0.35 0.4)
			(stroke
				(width 0.15)
				(type solid)
			)
			(layer "F.Fab")
		)
		(fp_line
			(start 0.65 -0.425)
			(end 0.65 0.423)
			(stroke
				(width 0.15)
				(type solid)
			)
			(layer "F.Fab")
		)
		(pad "1" smd roundrect
			(at -0.701 0)
			(size 0.5 0.6)
			(layers "F.Cu" "F.Mask" "F.Paste")
			(roundrect_rratio 0.25)
			(net 2 "+3V3")
			(pinfunction "C")
			(pintype "passive")
			(teardrops
				(best_length_ratio 0.2)
				(max_length 1)
				(best_width_ratio 0.9)
				(max_width 2)
				(curved_edges yes)
				(filter_ratio 0.9)
				(enabled yes)
				(allow_two_segments yes)
				(prefer_zone_connections yes)
			)
		)
		(pad "2" smd roundrect
			(at 0.699 0)
			(size 0.5 0.6)
			(layers "F.Cu" "F.Mask" "F.Paste")
			(roundrect_rratio 0.25)
			(net 1 "GND")
			(pinfunction "A")
			(pintype "passive")
			(teardrops
				(best_length_ratio 0.2)
				(max_length 1)
				(best_width_ratio 0.9)
				(max_width 2)
				(curved_edges yes)
				(filter_ratio 0.9)
				(enabled yes)
				(allow_two_segments yes)
				(prefer_zone_connections yes)
			)
		)
	)
	(footprint "antmicro-footprints:C_0402_1005Metric"
		(layer "F.Cu")
		(at 109.756999 74.876 -90)
		(descr "Capacitor SMD 0402")
		(tags "capacitor SMD 0402")
		(property "Reference" "C30"
			(at -1.316 0.456999 90)
			(layer "F.SilkS")
			(effects
				(font
					(size 0.7 0.7)
					(thickness 0.15)
				)
				(justify right bottom)
			)
		)
		(property "Value" "C_47p_0402"
			(at -1.022927 2.155213 90)
			(layer "F.Fab")
			(effects
				(font
					(size 0.7 0.7)
					(thickness 0.15)
				)
				(justify right bottom)
			)
		)
		(property "Datasheet" "https://www.kemet.com/en/us/capacitors/product/C0402C470J5GACTU.html"
			(at 0 0 270)
			(layer "F.Fab")
			(hide yes)
			(effects
				(font
					(size 1.27 1.27)
					(thickness 0.15)
				)
			)
		)
		(property "Author" "Antmicro"
			(at 34.880999 184.632999 0)
			(layer "F.Fab")
			(hide yes)
			(effects
				(font
					(size 1 1)
					(thickness 0.15)
				)
			)
		)
		(property "Dielectric" "C0G"
			(at 34.880999 184.632999 0)
			(layer "F.Fab")
			(hide yes)
			(effects
				(font
					(size 1 1)
					(thickness 0.15)
				)
			)
		)
		(property "License" "Apache-2.0"
			(at 34.880999 184.632999 0)
			(layer "F.Fab")
			(hide yes)
			(effects
				(font
					(size 1 1)
					(thickness 0.15)
				)
			)
		)
		(property "MPN" "C0402C470J5GACTU"
			(at 34.880999 184.632999 0)
			(layer "F.Fab")
			(hide yes)
			(effects
				(font
					(size 1 1)
					(thickness 0.15)
				)
			)
		)
		(property "Manufacturer" "KEMET"
			(at 34.880999 184.632999 0)
			(layer "F.Fab")
			(hide yes)
			(effects
				(font
					(size 1 1)
					(thickness 0.15)
				)
			)
		)
		(property "Public" "False"
			(at 34.880999 184.632999 0)
			(layer "F.Fab")
			(hide yes)
			(effects
				(font
					(size 1 1)
					(thickness 0.15)
				)
			)
		)
		(property "Val" "47p"
			(at 34.880999 184.632999 0)
			(layer "F.Fab")
			(hide yes)
			(effects
				(font
					(size 1 1)
					(thickness 0.15)
				)
			)
		)
		(property "Voltage" ""
			(at 34.880999 184.632999 0)
			(layer "F.Fab")
			(hide yes)
			(effects
				(font
					(size 1 1)
					(thickness 0.15)
				)
			)
		)
		(sheetname "USB-C console")
		(sheetfile "usb-c_console.kicad_sch")
		(attr smd)
		(fp_rect
			(start -0.925 -0.47)
			(end 0.925 0.47)
			(stroke
				(width 0.05)
				(type default)
			)
			(fill no)
			(layer "F.CrtYd")
		)
		(fp_line
			(start -0.494 0.248)
			(end -0.494 -0.25)
			(stroke
				(width 0.15)
				(type solid)
			)
			(layer "F.Fab")
		)
		(fp_line
			(start 0.504 0.248)
			(end -0.494 0.248)
			(stroke
				(width 0.15)
				(type solid)
			)
			(layer "F.Fab")
		)
		(fp_line
			(start -0.494 -0.25)
			(end 0.504 -0.25)
			(stroke
				(width 0.15)
				(type solid)
			)
			(layer "F.Fab")
		)
		(fp_line
			(start 0.504 -0.25)
			(end 0.504 0.248)
			(stroke
				(width 0.15)
				(type solid)
			)
			(layer "F.Fab")
		)
		(pad "1" smd roundrect
			(at -0.48 0 270)
			(size 0.59 0.64)
			(layers "F.Cu" "F.Mask" "F.Paste")
			(roundrect_rratio 0.25)
			(net 1 "GND")
			(pintype "passive")
			(teardrops
				(best_length_ratio 0.2)
				(max_length 1)
				(best_width_ratio 0.9)
				(max_width 2)
				(curved_edges yes)
				(filter_ratio 0.9)
				(enabled yes)
				(allow_two_segments yes)
				(prefer_zone_connections yes)
			)
		)
		(pad "2" smd roundrect
			(at 0.48 0 270)
			(size 0.59 0.64)
			(layers "F.Cu" "F.Mask" "F.Paste")
			(roundrect_rratio 0.25)
			(net 55 "/USB-C console/USB_D+")
			(pintype "passive")
			(teardrops
				(best_length_ratio 0.2)
				(max_length 1)
				(best_width_ratio 0.9)
				(max_width 2)
				(curved_edges yes)
				(filter_ratio 0.9)
				(enabled yes)
				(allow_two_segments yes)
				(prefer_zone_connections yes)
			)
		)
	)
)
